(kicad_pcb
	(version 20260206)
	(generator "pcbnew")
	(generator_version "10.0")
	(general
		(thickness 1.6)
		(legacy_teardrops no)
	)
	(paper "A4")
	(title_block
		(title "Bryce Canyon_SCC_16316-1_OCP.brd")
		(comment 1 "Bryce Canyon / footprints 829-836 of 1561")
	)
	(layers
		(0 "F.Cu" signal "TOP")
		(4 "In1.Cu" signal "L2GND")
		(6 "In2.Cu" signal "L3")
		(8 "In3.Cu" signal "L4VCC")
		(10 "In4.Cu" signal "L5VCC")
		(12 "In5.Cu" signal "L6")
		(14 "In6.Cu" signal "L7GND")
		(2 "B.Cu" signal "BOTTOM")
		(9 "F.Adhes" user "F.Adhesive")
		(11 "B.Adhes" user "B.Adhesive")
		(13 "F.Paste" user "Package Geometry/Pastemask Top")
		(15 "B.Paste" user "Package Geometry/Pastemask Bottom")
		(5 "F.SilkS" user "Ref Des/Silkscreen Top")
		(7 "B.SilkS" user "Ref Des/Silkscreen Bottom")
		(1 "F.Mask" user "Board Geometry/Soldermask Top")
		(3 "B.Mask" user "Board Geometry/Soldermask Bottom")
		(17 "Dwgs.User" user "User.Drawings")
		(19 "Cmts.User" user "User.Comments")
		(21 "Eco1.User" user "User.Eco1")
		(23 "Eco2.User" user "User.Eco2")
		(25 "Edge.Cuts" user "Board Geometry/Outline")
		(27 "Margin" user)
		(31 "F.CrtYd" user "Package Geometry/Place Bound Top")
		(29 "B.CrtYd" user "Package Geometry/Place Bound Bottom")
		(35 "F.Fab" user "Ref Des/Assembly Top")
		(33 "B.Fab" user "Ref Des/Assembly Bottom")
	)
	(footprint ""
		(layer "B.Cu")
		(at 120.5484 -64.7192 -90)
		(property "Reference" "C218"
			(at 0 0 90)
			(layer "B.SilkS")
			(hide yes)
			(effects
				(font
					(size 1.27 1.27)
				)
				(justify mirror)
			)
		)
		(property "Value" "SCD1U16V2KX-3GP"
			(at -1.1811 -2.7051 270)
			(unlocked yes)
			(layer "B.Fab")
			(hide yes)
			(effects
				(font
					(size 1.016 1.016)
					(thickness 0.1524)
				)
				(justify mirror)
			)
		)
		(property "Device Type" "C402H22"
			(at -1.1811 -4.2291 270)
			(unlocked yes)
			(layer "B.Fab")
			(hide yes)
			(effects
				(font
					(size 1.016 1.016)
					(thickness 0.1524)
				)
				(justify mirror)
			)
		)
		(duplicate_pad_numbers_are_jumpers no)
		(fp_rect
			(start 0.4318 0.9525)
			(end -0.4318 -0.9525)
			(stroke
				(width 0)
				(type default)
			)
			(fill no)
			(layer "B.CrtYd")
		)
		(fp_rect
			(start 0.4318 0.9525)
			(end -0.4318 -0.9525)
			(stroke
				(width 0)
				(type default)
			)
			(fill no)
			(layer "B.Fab")
		)
		(pad "1" smd custom
			(at 0 -0.4445 90)
			(size 0.1524 0.1524)
			(layers "B.Cu" "B.Mask" "B.Paste")
			(net "GB_VDDH")
			(options
				(clearance outline)
				(anchor circle)
			)
			(primitives
				(gr_poly
					(pts
						(arc
							(start 0.3048 0.2032)
							(mid 0.275042 0.275042)
							(end 0.2032 0.3048)
						)
						(arc
							(start -0.2032 0.3048)
							(mid -0.275042 0.275042)
							(end -0.3048 0.2032)
						)
						(arc
							(start -0.3048 -0.2032)
							(mid -0.275042 -0.275042)
							(end -0.2032 -0.3048)
						)
						(arc
							(start 0.2032 -0.3048)
							(mid 0.275042 -0.275042)
							(end 0.3048 -0.2032)
						)
					)
					(width 0)
					(fill yes)
				)
			)
		)
		(pad "2" smd custom
			(at 0 0.4445 90)
			(size 0.1524 0.1524)
			(layers "B.Cu" "B.Mask" "B.Paste")
			(net "GND")
			(options
				(clearance outline)
				(anchor circle)
			)
			(primitives
				(gr_poly
					(pts
						(arc
							(start 0.3048 0.2032)
							(mid 0.275042 0.275042)
							(end 0.2032 0.3048)
						)
						(arc
							(start -0.2032 0.3048)
							(mid -0.275042 0.275042)
							(end -0.3048 0.2032)
						)
						(arc
							(start -0.3048 -0.2032)
							(mid -0.275042 -0.275042)
							(end -0.2032 -0.3048)
						)
						(arc
							(start 0.2032 -0.3048)
							(mid 0.275042 -0.275042)
							(end 0.3048 -0.2032)
						)
					)
					(width 0)
					(fill yes)
				)
			)
		)
	)
	(footprint ""
		(layer "B.Cu")
		(at 96.497394 -51.763168 90)
		(property "Reference" "C91"
			(at 0 0 90)
			(layer "B.SilkS")
			(hide yes)
			(effects
				(font
					(size 1.27 1.27)
				)
				(justify mirror)
			)
		)
		(property "Value" "SCD01U16V1KX-GP"
			(at 2.8321 -1.7399 90)
			(unlocked yes)
			(layer "B.Fab")
			(hide yes)
			(effects
				(font
					(size 1.016 1.016)
					(thickness 0.1524)
				)
				(justify mirror)
			)
		)
		(property "Device Type" "C0201H13"
			(at 2.8321 -3.2639 90)
			(unlocked yes)
			(layer "B.Fab")
			(hide yes)
			(effects
				(font
					(size 1.016 1.016)
					(thickness 0.1524)
				)
				(justify mirror)
			)
		)
		(duplicate_pad_numbers_are_jumpers no)
		(fp_rect
			(start 0.2794 0.6477)
			(end -0.2794 -0.6477)
			(stroke
				(width 0)
				(type default)
			)
			(fill no)
			(layer "B.CrtYd")
		)
		(fp_rect
			(start 0.2794 0.6477)
			(end -0.2794 -0.6477)
			(stroke
				(width 0)
				(type default)
			)
			(fill no)
			(layer "B.Fab")
		)
		(pad "1" smd custom
			(at 0 -0.2794 270)
			(size 0.0762 0.0762)
			(layers "B.Cu" "B.Mask" "B.Paste")
			(net "PHY_DPB_TO_SCC_14_DP")
			(options
				(clearance outline)
				(anchor circle)
			)
			(primitives
				(gr_poly
					(pts
						(arc
							(start 0.1524 0.127)
							(mid 0.137521 0.162921)
							(end 0.1016 0.1778)
						)
						(arc
							(start -0.1016 0.1778)
							(mid -0.137521 0.162921)
							(end -0.1524 0.127)
						)
						(arc
							(start -0.1524 -0.127)
							(mid -0.137521 -0.162921)
							(end -0.1016 -0.1778)
						)
						(arc
							(start 0.1016 -0.1778)
							(mid 0.137521 -0.162921)
							(end 0.1524 -0.127)
						)
					)
					(width 0)
					(fill yes)
				)
			)
		)
		(pad "2" smd custom
			(at 0 0.2794 270)
			(size 0.0762 0.0762)
			(layers "B.Cu" "B.Mask" "B.Paste")
			(net "PHY_DPB_TO_SCC_C_14_DP")
			(options
				(clearance outline)
				(anchor circle)
			)
			(primitives
				(gr_poly
					(pts
						(arc
							(start 0.1524 0.127)
							(mid 0.137521 0.162921)
							(end 0.1016 0.1778)
						)
						(arc
							(start -0.1016 0.1778)
							(mid -0.137521 0.162921)
							(end -0.1524 0.127)
						)
						(arc
							(start -0.1524 -0.127)
							(mid -0.137521 -0.162921)
							(end -0.1016 -0.1778)
						)
						(arc
							(start 0.1016 -0.1778)
							(mid 0.137521 -0.162921)
							(end 0.1524 -0.127)
						)
					)
					(width 0)
					(fill yes)
				)
			)
		)
	)
	(footprint ""
		(layer "B.Cu")
		(at 120.52808 -72.263)
		(property "Reference" "C124"
			(at 0 0 0)
			(layer "B.SilkS")
			(hide yes)
			(effects
				(font
					(size 1.27 1.27)
				)
				(justify mirror)
			)
		)
		(property "Value" "SC1KP25V1KX-GP"
			(at 2.8321 -1.7399 0)
			(unlocked yes)
			(layer "B.Fab")
			(hide yes)
			(effects
				(font
					(size 1.016 1.016)
					(thickness 0.1524)
				)
				(justify mirror)
			)
		)
		(property "Device Type" "C0201H13"
			(at 2.8321 -3.2639 0)
			(unlocked yes)
			(layer "B.Fab")
			(hide yes)
			(effects
				(font
					(size 1.016 1.016)
					(thickness 0.1524)
				)
				(justify mirror)
			)
		)
		(duplicate_pad_numbers_are_jumpers no)
		(fp_rect
			(start 0.2794 0.6477)
			(end -0.2794 -0.6477)
			(stroke
				(width 0)
				(type default)
			)
			(fill no)
			(layer "B.CrtYd")
		)
		(fp_rect
			(start 0.2794 0.6477)
			(end -0.2794 -0.6477)
			(stroke
				(width 0)
				(type default)
			)
			(fill no)
			(layer "B.Fab")
		)
		(pad "1" smd custom
			(at 0 -0.2794 180)
			(size 0.0762 0.0762)
			(layers "B.Cu" "B.Mask" "B.Paste")
			(net "P1V8_E")
			(options
				(clearance outline)
				(anchor circle)
			)
			(primitives
				(gr_poly
					(pts
						(arc
							(start 0.1524 0.127)
							(mid 0.137521 0.162921)
							(end 0.1016 0.1778)
						)
						(arc
							(start -0.1016 0.1778)
							(mid -0.137521 0.162921)
							(end -0.1524 0.127)
						)
						(arc
							(start -0.1524 -0.127)
							(mid -0.137521 -0.162921)
							(end -0.1016 -0.1778)
						)
						(arc
							(start 0.1016 -0.1778)
							(mid 0.137521 -0.162921)
							(end 0.1524 -0.127)
						)
					)
					(width 0)
					(fill yes)
				)
			)
		)
		(pad "2" smd custom
			(at 0 0.2794 180)
			(size 0.0762 0.0762)
			(layers "B.Cu" "B.Mask" "B.Paste")
			(net "GND")
			(options
				(clearance outline)
				(anchor circle)
			)
			(primitives
				(gr_poly
					(pts
						(arc
							(start 0.1524 0.127)
							(mid 0.137521 0.162921)
							(end 0.1016 0.1778)
						)
						(arc
							(start -0.1016 0.1778)
							(mid -0.137521 0.162921)
							(end -0.1524 0.127)
						)
						(arc
							(start -0.1524 -0.127)
							(mid -0.137521 -0.162921)
							(end -0.1016 -0.1778)
						)
						(arc
							(start 0.1016 -0.1778)
							(mid 0.137521 -0.162921)
							(end 0.1524 -0.127)
						)
					)
					(width 0)
					(fill yes)
				)
			)
		)
	)
	(footprint ""
		(layer "B.Cu")
		(at 179.430934 -40.289226 90)
		(property "Reference" "C440"
			(at 0 0 90)
			(layer "B.SilkS")
			(hide yes)
			(effects
				(font
					(size 1.27 1.27)
				)
				(justify mirror)
			)
		)
		(property "Value" "SCD1U6D3V1KX-GP"
			(at 2.8321 -1.7399 90)
			(unlocked yes)
			(layer "B.Fab")
			(hide yes)
			(effects
				(font
					(size 1.016 1.016)
					(thickness 0.1524)
				)
				(justify mirror)
			)
		)
		(property "Device Type" "C0201H13"
			(at 2.8321 -3.2639 90)
			(unlocked yes)
			(layer "B.Fab")
			(hide yes)
			(effects
				(font
					(size 1.016 1.016)
					(thickness 0.1524)
				)
				(justify mirror)
			)
		)
		(duplicate_pad_numbers_are_jumpers no)
		(fp_rect
			(start 0.2794 0.6477)
			(end -0.2794 -0.6477)
			(stroke
				(width 0)
				(type default)
			)
			(fill no)
			(layer "B.CrtYd")
		)
		(fp_rect
			(start 0.2794 0.6477)
			(end -0.2794 -0.6477)
			(stroke
				(width 0)
				(type default)
			)
			(fill no)
			(layer "B.Fab")
		)
		(pad "1" smd custom
			(at 0 -0.2794 270)
			(size 0.0762 0.0762)
			(layers "B.Cu" "B.Mask" "B.Paste")
			(net "P0V975")
			(options
				(clearance outline)
				(anchor circle)
			)
			(primitives
				(gr_poly
					(pts
						(arc
							(start 0.1524 0.127)
							(mid 0.137521 0.162921)
							(end 0.1016 0.1778)
						)
						(arc
							(start -0.1016 0.1778)
							(mid -0.137521 0.162921)
							(end -0.1524 0.127)
						)
						(arc
							(start -0.1524 -0.127)
							(mid -0.137521 -0.162921)
							(end -0.1016 -0.1778)
						)
						(arc
							(start 0.1016 -0.1778)
							(mid 0.137521 -0.162921)
							(end 0.1524 -0.127)
						)
					)
					(width 0)
					(fill yes)
				)
			)
		)
		(pad "2" smd custom
			(at 0 0.2794 270)
			(size 0.0762 0.0762)
			(layers "B.Cu" "B.Mask" "B.Paste")
			(net "GND")
			(options
				(clearance outline)
				(anchor circle)
			)
			(primitives
				(gr_poly
					(pts
						(arc
							(start 0.1524 0.127)
							(mid 0.137521 0.162921)
							(end 0.1016 0.1778)
						)
						(arc
							(start -0.1016 0.1778)
							(mid -0.137521 0.162921)
							(end -0.1524 0.127)
						)
						(arc
							(start -0.1524 -0.127)
							(mid -0.137521 -0.162921)
							(end -0.1016 -0.1778)
						)
						(arc
							(start 0.1016 -0.1778)
							(mid 0.137521 -0.162921)
							(end 0.1524 -0.127)
						)
					)
					(width 0)
					(fill yes)
				)
			)
		)
	)
	(footprint ""
		(layer "B.Cu")
		(at 116.5098 -70.3834 180)
		(property "Reference" "C173"
			(at 0 0 0)
			(layer "B.SilkS")
			(hide yes)
			(effects
				(font
					(size 1.27 1.27)
				)
				(justify mirror)
			)
		)
		(property "Value" "SCD1U6D3V1KX-GP"
			(at 2.8321 -1.7399 180)
			(unlocked yes)
			(layer "B.Fab")
			(hide yes)
			(effects
				(font
					(size 1.016 1.016)
					(thickness 0.1524)
				)
				(justify mirror)
			)
		)
		(property "Device Type" "C0201H13"
			(at 2.8321 -3.2639 180)
			(unlocked yes)
			(layer "B.Fab")
			(hide yes)
			(effects
				(font
					(size 1.016 1.016)
					(thickness 0.1524)
				)
				(justify mirror)
			)
		)
		(duplicate_pad_numbers_are_jumpers no)
		(fp_rect
			(start 0.2794 0.6477)
			(end -0.2794 -0.6477)
			(stroke
				(width 0)
				(type default)
			)
			(fill no)
			(layer "B.CrtYd")
		)
		(fp_rect
			(start 0.2794 0.6477)
			(end -0.2794 -0.6477)
			(stroke
				(width 0)
				(type default)
			)
			(fill no)
			(layer "B.Fab")
		)
		(pad "1" smd custom
			(at 0 -0.2794)
			(size 0.0762 0.0762)
			(layers "B.Cu" "B.Mask" "B.Paste")
			(net "P0V9")
			(options
				(clearance outline)
				(anchor circle)
			)
			(primitives
				(gr_poly
					(pts
						(arc
							(start 0.1524 0.127)
							(mid 0.137521 0.162921)
							(end 0.1016 0.1778)
						)
						(arc
							(start -0.1016 0.1778)
							(mid -0.137521 0.162921)
							(end -0.1524 0.127)
						)
						(arc
							(start -0.1524 -0.127)
							(mid -0.137521 -0.162921)
							(end -0.1016 -0.1778)
						)
						(arc
							(start 0.1016 -0.1778)
							(mid 0.137521 -0.162921)
							(end 0.1524 -0.127)
						)
					)
					(width 0)
					(fill yes)
				)
			)
		)
		(pad "2" smd custom
			(at 0 0.2794)
			(size 0.0762 0.0762)
			(layers "B.Cu" "B.Mask" "B.Paste")
			(net "GND")
			(options
				(clearance outline)
				(anchor circle)
			)
			(primitives
				(gr_poly
					(pts
						(arc
							(start 0.1524 0.127)
							(mid 0.137521 0.162921)
							(end 0.1016 0.1778)
						)
						(arc
							(start -0.1016 0.1778)
							(mid -0.137521 0.162921)
							(end -0.1524 0.127)
						)
						(arc
							(start -0.1524 -0.127)
							(mid -0.137521 -0.162921)
							(end -0.1016 -0.1778)
						)
						(arc
							(start 0.1016 -0.1778)
							(mid 0.137521 -0.162921)
							(end 0.1524 -0.127)
						)
					)
					(width 0)
					(fill yes)
				)
			)
		)
	)
	(footprint ""
		(layer "B.Cu")
		(at 133.5913 -120.904 -90)
		(property "Reference" "R602"
			(at 0 0 90)
			(layer "B.SilkS")
			(hide yes)
			(effects
				(font
					(size 1.27 1.27)
				)
				(justify mirror)
			)
		)
		(property "Value" "4K7R2F-GP"
			(at -0.064008 -3.993896 270)
			(unlocked yes)
			(layer "B.Fab")
			(hide yes)
			(effects
				(font
					(size 1.016 1.016)
					(thickness 0.1524)
				)
				(justify mirror)
			)
		)
		(property "Device Type" "R402H16"
			(at -0.064008 -5.517896 270)
			(unlocked yes)
			(layer "B.Fab")
			(hide yes)
			(effects
				(font
					(size 1.016 1.016)
					(thickness 0.1524)
				)
				(justify mirror)
			)
		)
		(duplicate_pad_numbers_are_jumpers no)
		(fp_line
			(start -0.508 -0.9398)
			(end 0.508 -0.9398)
			(stroke
				(width 0.1524)
				(type default)
			)
			(layer "B.SilkS")
		)
		(fp_line
			(start 0.508 -0.9398)
			(end 0.508 0.9398)
			(stroke
				(width 0.1524)
				(type default)
			)
			(layer "B.SilkS")
		)
		(fp_rect
			(start 0.508 0.9398)
			(end -0.508 -0.9398)
			(stroke
				(width 0)
				(type default)
			)
			(fill no)
			(layer "B.CrtYd")
		)
		(fp_rect
			(start 0.508 0.9398)
			(end -0.508 -0.9398)
			(stroke
				(width 0)
				(type default)
			)
			(fill no)
			(layer "B.Fab")
		)
		(pad "1" smd custom
			(at 0 -0.4445 90)
			(size 0.1397 0.1397)
			(layers "B.Cu" "B.Mask" "B.Paste")
			(net "P1V5_C_G")
			(options
				(clearance outline)
				(anchor circle)
			)
			(primitives
				(gr_poly
					(pts
						(arc
							(start -0.1778 0.2794)
							(mid -0.249642 0.249642)
							(end -0.2794 0.1778)
						)
						(arc
							(start -0.2794 -0.1778)
							(mid -0.249642 -0.249642)
							(end -0.1778 -0.2794)
						)
						(arc
							(start 0.1778 -0.2794)
							(mid 0.249642 -0.249642)
							(end 0.2794 -0.1778)
						)
						(arc
							(start 0.2794 0.1778)
							(mid 0.249642 0.249642)
							(end 0.1778 0.2794)
						)
					)
					(width 0)
					(fill yes)
				)
			)
		)
		(pad "2" smd custom
			(at 0 0.4445 90)
			(size 0.1397 0.1397)
			(layers "B.Cu" "B.Mask" "B.Paste")
			(net "P1V5_C")
			(options
				(clearance outline)
				(anchor circle)
			)
			(primitives
				(gr_poly
					(pts
						(arc
							(start -0.1778 0.2794)
							(mid -0.249642 0.249642)
							(end -0.2794 0.1778)
						)
						(arc
							(start -0.2794 -0.1778)
							(mid -0.249642 -0.249642)
							(end -0.1778 -0.2794)
						)
						(arc
							(start 0.1778 -0.2794)
							(mid 0.249642 -0.249642)
							(end 0.2794 -0.1778)
						)
						(arc
							(start 0.2794 0.1778)
							(mid 0.249642 0.249642)
							(end 0.1778 0.2794)
						)
					)
					(width 0)
					(fill yes)
				)
			)
		)
	)
	(footprint ""
		(layer "B.Cu")
		(at 115.40236 -59.4487)
		(property "Reference" "C584"
			(at 0 0 0)
			(layer "B.SilkS")
			(hide yes)
			(effects
				(font
					(size 1.27 1.27)
				)
				(justify mirror)
			)
		)
		(property "Value" "SCD1U6D3V1KX-GP"
			(at 2.8321 -1.7399 0)
			(unlocked yes)
			(layer "B.Fab")
			(hide yes)
			(effects
				(font
					(size 1.016 1.016)
					(thickness 0.1524)
				)
				(justify mirror)
			)
		)
		(property "Device Type" "C0201H13"
			(at 2.8321 -3.2639 0)
			(unlocked yes)
			(layer "B.Fab")
			(hide yes)
			(effects
				(font
					(size 1.016 1.016)
					(thickness 0.1524)
				)
				(justify mirror)
			)
		)
		(duplicate_pad_numbers_are_jumpers no)
		(fp_rect
			(start 0.2794 0.6477)
			(end -0.2794 -0.6477)
			(stroke
				(width 0)
				(type default)
			)
			(fill no)
			(layer "B.CrtYd")
		)
		(fp_rect
			(start 0.2794 0.6477)
			(end -0.2794 -0.6477)
			(stroke
				(width 0)
				(type default)
			)
			(fill no)
			(layer "B.Fab")
		)
		(pad "1" smd custom
			(at 0 -0.2794 180)
			(size 0.0762 0.0762)
			(layers "B.Cu" "B.Mask" "B.Paste")
			(net "GB_VDDA")
			(options
				(clearance outline)
				(anchor circle)
			)
			(primitives
				(gr_poly
					(pts
						(arc
							(start 0.1524 0.127)
							(mid 0.137521 0.162921)
							(end 0.1016 0.1778)
						)
						(arc
							(start -0.1016 0.1778)
							(mid -0.137521 0.162921)
							(end -0.1524 0.127)
						)
						(arc
							(start -0.1524 -0.127)
							(mid -0.137521 -0.162921)
							(end -0.1016 -0.1778)
						)
						(arc
							(start 0.1016 -0.1778)
							(mid 0.137521 -0.162921)
							(end 0.1524 -0.127)
						)
					)
					(width 0)
					(fill yes)
				)
			)
		)
		(pad "2" smd custom
			(at 0 0.2794 180)
			(size 0.0762 0.0762)
			(layers "B.Cu" "B.Mask" "B.Paste")
			(net "GND")
			(options
				(clearance outline)
				(anchor circle)
			)
			(primitives
				(gr_poly
					(pts
						(arc
							(start 0.1524 0.127)
							(mid 0.137521 0.162921)
							(end 0.1016 0.1778)
						)
						(arc
							(start -0.1016 0.1778)
							(mid -0.137521 0.162921)
							(end -0.1524 0.127)
						)
						(arc
							(start -0.1524 -0.127)
							(mid -0.137521 -0.162921)
							(end -0.1016 -0.1778)
						)
						(arc
							(start 0.1016 -0.1778)
							(mid 0.137521 -0.162921)
							(end 0.1524 -0.127)
						)
					)
					(width 0)
					(fill yes)
				)
			)
		)
	)
	(footprint ""
		(layer "B.Cu")
		(at 177.771806 -43.139868 90)
		(property "Reference" "C450"
			(at 0 0 90)
			(layer "B.SilkS")
			(hide yes)
			(effects
				(font
					(size 1.27 1.27)
				)
				(justify mirror)
			)
		)
		(property "Value" "SC1KP50V2KX-1GP"
			(at -1.1811 -2.7051 90)
			(unlocked yes)
			(layer "B.Fab")
			(hide yes)
			(effects
				(font
					(size 1.016 1.016)
					(thickness 0.1524)
				)
				(justify mirror)
			)
		)
		(property "Device Type" "C402H22"
			(at -1.1811 -4.2291 90)
			(unlocked yes)
			(layer "B.Fab")
			(hide yes)
			(effects
				(font
					(size 1.016 1.016)
					(thickness 0.1524)
				)
				(justify mirror)
			)
		)
		(duplicate_pad_numbers_are_jumpers no)
		(fp_rect
			(start 0.4318 0.9525)
			(end -0.4318 -0.9525)
			(stroke
				(width 0)
				(type default)
			)
			(fill no)
			(layer "B.CrtYd")
		)
		(fp_rect
			(start 0.4318 0.9525)
			(end -0.4318 -0.9525)
			(stroke
				(width 0)
				(type default)
			)
			(fill no)
			(layer "B.Fab")
		)
		(pad "1" smd custom
			(at 0 -0.4445 270)
			(size 0.1524 0.1524)
			(layers "B.Cu" "B.Mask" "B.Paste")
			(net "P0V975")
			(options
				(clearance outline)
				(anchor circle)
			)
			(primitives
				(gr_poly
					(pts
						(arc
							(start 0.3048 0.2032)
							(mid 0.275042 0.275042)
							(end 0.2032 0.3048)
						)
						(arc
							(start -0.2032 0.3048)
							(mid -0.275042 0.275042)
							(end -0.3048 0.2032)
						)
						(arc
							(start -0.3048 -0.2032)
							(mid -0.275042 -0.275042)
							(end -0.2032 -0.3048)
						)
						(arc
							(start 0.2032 -0.3048)
							(mid 0.275042 -0.275042)
							(end 0.3048 -0.2032)
						)
					)
					(width 0)
					(fill yes)
				)
			)
		)
		(pad "2" smd custom
			(at 0 0.4445 270)
			(size 0.1524 0.1524)
			(layers "B.Cu" "B.Mask" "B.Paste")
			(net "GND")
			(options
				(clearance outline)
				(anchor circle)
			)
			(primitives
				(gr_poly
					(pts
						(arc
							(start 0.3048 0.2032)
							(mid 0.275042 0.275042)
							(end 0.2032 0.3048)
						)
						(arc
							(start -0.2032 0.3048)
							(mid -0.275042 0.275042)
							(end -0.3048 0.2032)
						)
						(arc
							(start -0.3048 -0.2032)
							(mid -0.275042 -0.275042)
							(end -0.2032 -0.3048)
						)
						(arc
							(start 0.2032 -0.3048)
							(mid 0.275042 -0.275042)
							(end 0.3048 -0.2032)
						)
					)
					(width 0)
					(fill yes)
				)
			)
		)
	)
)
